(kicad_pcb
	(version 20241229)
	(generator "pcbnew")
	(generator_version "9.0")
	(general
		(thickness 1.62)
		(legacy_teardrops no)
	)
	(paper "A3")
	(title_block
		(title "COM Express 7 Baseboard")
		(date "2025-02-04")
		(rev "1.1.2")
		(company "Antmicro Ltd")
		(comment 1 "www.antmicro.com")
		(comment 9 "footprint 486 of 802 (U45), pads 1-39 of 144")
	)
	(layers
		(0 "F.Cu" signal)
		(4 "In1.Cu" signal)
		(6 "In2.Cu" signal)
		(8 "In3.Cu" signal)
		(10 "In4.Cu" signal)
		(12 "In5.Cu" signal)
		(14 "In6.Cu" signal)
		(2 "B.Cu" signal)
		(9 "F.Adhes" user "F.Adhesive")
		(11 "B.Adhes" user "B.Adhesive")
		(13 "F.Paste" user)
		(15 "B.Paste" user)
		(5 "F.SilkS" user "F.Silkscreen")
		(7 "B.SilkS" user "B.Silkscreen")
		(1 "F.Mask" user)
		(3 "B.Mask" user)
		(17 "Dwgs.User" user "User.Drawings")
		(19 "Cmts.User" user "User.Comments")
		(21 "Eco1.User" user "User.Eco1")
		(23 "Eco2.User" user "User.Eco2")
		(25 "Edge.Cuts" user)
		(27 "Margin" user)
		(31 "F.CrtYd" user "F.Courtyard")
		(29 "B.CrtYd" user "B.Courtyard")
		(35 "F.Fab" user)
		(33 "B.Fab" user)
	)
	(footprint "antmicro-footprints:BGA-144_12x12_13.05x13.05mm_P1.0mm"
		(layer "F.Cu")
		(at 132.79 137.36 -90)
		(property "Reference" "U45"
			(at 7.9 4.85 180)
			(layer "F.SilkS")
			(effects
				(font
					(size 0.7 0.7)
					(thickness 0.15)
				)
				(justify right bottom)
			)
		)
		(property "Value" "TLK10232CTR"
			(at 0 7.525 90)
			(layer "F.Fab")
			(effects
				(font
					(size 0.7 0.7)
					(thickness 0.15)
				)
				(justify right bottom)
			)
		)
		(property "Datasheet" "https://www.ti.com/lit/ds/symlink/tlk10232.pdf?ts=1712150848075&ref_url=https%253A%252F%252Fwww.mouser.pl%252F"
			(at 0 0 270)
			(layer "F.Fab")
			(hide yes)
			(effects
				(font
					(size 1.27 1.27)
					(thickness 0.15)
				)
			)
		)
		(property "Author" "Antmicro"
			(at -4.57 270.15 0)
			(layer "F.Fab")
			(hide yes)
			(effects
				(font
					(size 1 1)
					(thickness 0.15)
				)
			)
		)
		(property "License" "Apache-2.0"
			(at -4.57 270.15 0)
			(layer "F.Fab")
			(hide yes)
			(effects
				(font
					(size 1 1)
					(thickness 0.15)
				)
			)
		)
		(property "MPN" "TLK10232CTR"
			(at -4.57 270.15 0)
			(layer "F.Fab")
			(hide yes)
			(effects
				(font
					(size 1 1)
					(thickness 0.15)
				)
			)
		)
		(property "Manufacturer" "Texas Instruments"
			(at -4.57 270.15 0)
			(layer "F.Fab")
			(hide yes)
			(effects
				(font
					(size 1 1)
					(thickness 0.15)
				)
			)
		)
		(sheetname "KR to SFI #2")
		(sheetfile "kr_sfi.kicad_sch")
		(attr smd)
		(pad "A1" smd circle
			(at -5.5 -5.5 270)
			(size 0.5 0.5)
			(layers "F.Cu" "F.Mask" "F.Paste")
			(net 832 "unconnected-(U45A-INA1+-PadA1)")
			(pinfunction "INA1+")
			(pintype "input+no_connect")
			(solder_mask_margin 0.05)
			(teardrops
				(best_length_ratio 0.4)
				(max_length 1)
				(best_width_ratio 0.9)
				(max_width 2)
				(curved_edges yes)
				(filter_ratio 0.9)
				(enabled yes)
				(allow_two_segments yes)
				(prefer_zone_connections yes)
			)
		)
		(pad "A2" smd circle
			(at -4.5 -5.5 270)
			(size 0.5 0.5)
			(layers "F.Cu" "F.Mask" "F.Paste")
			(net 1 "GND")
			(pinfunction "GND")
			(pintype "passive")
			(solder_mask_margin 0.05)
			(teardrops
				(best_length_ratio 0.4)
				(max_length 1)
				(best_width_ratio 0.9)
				(max_width 2)
				(curved_edges yes)
				(filter_ratio 0.9)
				(enabled yes)
				(allow_two_segments yes)
				(prefer_zone_connections yes)
			)
		)
		(pad "A3" smd circle
			(at -3.5 -5.5 270)
			(size 0.5 0.5)
			(layers "F.Cu" "F.Mask" "F.Paste")
			(net 833 "unconnected-(U45A-INA0--PadA3)")
			(pinfunction "INA0-")
			(pintype "input+no_connect")
			(solder_mask_margin 0.05)
			(teardrops
				(best_length_ratio 0.4)
				(max_length 1)
				(best_width_ratio 0.9)
				(max_width 2)
				(curved_edges yes)
				(filter_ratio 0.9)
				(enabled yes)
				(allow_two_segments yes)
				(prefer_zone_connections yes)
			)
		)
		(pad "A4" smd circle
			(at -2.5 -5.5 270)
			(size 0.5 0.5)
			(layers "F.Cu" "F.Mask" "F.Paste")
			(net 834 "unconnected-(U45A-INA0+-PadA4)")
			(pinfunction "INA0+")
			(pintype "input+no_connect")
			(solder_mask_margin 0.05)
			(teardrops
				(best_length_ratio 0.4)
				(max_length 1)
				(best_width_ratio 0.9)
				(max_width 2)
				(curved_edges yes)
				(filter_ratio 0.9)
				(enabled yes)
				(allow_two_segments yes)
				(prefer_zone_connections yes)
			)
		)
		(pad "A5" smd circle
			(at -1.5 -5.5 270)
			(size 0.5 0.5)
			(layers "F.Cu" "F.Mask" "F.Paste")
			(net 1 "GND")
			(pinfunction "GND")
			(pintype "passive")
			(solder_mask_margin 0.05)
			(teardrops
				(best_length_ratio 0.4)
				(max_length 1)
				(best_width_ratio 0.9)
				(max_width 2)
				(curved_edges yes)
				(filter_ratio 0.9)
				(enabled yes)
				(allow_two_segments yes)
				(prefer_zone_connections yes)
			)
		)
		(pad "A6" smd circle
			(at -0.5 -5.5 270)
			(size 0.5 0.5)
			(layers "F.Cu" "F.Mask" "F.Paste")
			(net 835 "unconnected-(U45A-OUTA0+-PadA6)")
			(pinfunction "OUTA0+")
			(pintype "output+no_connect")
			(solder_mask_margin 0.05)
			(teardrops
				(best_length_ratio 0.4)
				(max_length 1)
				(best_width_ratio 0.9)
				(max_width 2)
				(curved_edges yes)
				(filter_ratio 0.9)
				(enabled yes)
				(allow_two_segments yes)
				(prefer_zone_connections yes)
			)
		)
		(pad "A7" smd circle
			(at 0.5 -5.5 270)
			(size 0.5 0.5)
			(layers "F.Cu" "F.Mask" "F.Paste")
			(net 836 "unconnected-(U45A-OUTA0--PadA7)")
			(pinfunction "OUTA0-")
			(pintype "output+no_connect")
			(solder_mask_margin 0.05)
			(teardrops
				(best_length_ratio 0.4)
				(max_length 1)
				(best_width_ratio 0.9)
				(max_width 2)
				(curved_edges yes)
				(filter_ratio 0.9)
				(enabled yes)
				(allow_two_segments yes)
				(prefer_zone_connections yes)
			)
		)
		(pad "A8" smd circle
			(at 1.5 -5.5 270)
			(size 0.5 0.5)
			(layers "F.Cu" "F.Mask" "F.Paste")
			(net 678 "Net-(U45A-~{PDTRXA})")
			(pinfunction "~{PDTRXA}")
			(pintype "input")
			(solder_mask_margin 0.05)
			(teardrops
				(best_length_ratio 0.4)
				(max_length 1)
				(best_width_ratio 0.9)
				(max_width 2)
				(curved_edges yes)
				(filter_ratio 0.9)
				(enabled yes)
				(allow_two_segments yes)
				(prefer_zone_connections yes)
			)
		)
		(pad "A9" smd circle
			(at 2.5 -5.5 270)
			(size 0.5 0.5)
			(layers "F.Cu" "F.Mask" "F.Paste")
			(net 752 "Net-(U45C-CLKOUTB+)")
			(pinfunction "CLKOUTB+")
			(pintype "output")
			(solder_mask_margin 0.05)
			(teardrops
				(best_length_ratio 0.4)
				(max_length 1)
				(best_width_ratio 0.9)
				(max_width 2)
				(curved_edges yes)
				(filter_ratio 0.9)
				(enabled yes)
				(allow_two_segments yes)
				(prefer_zone_connections yes)
			)
		)
		(pad "A10" smd circle
			(at 3.5 -5.5 270)
			(size 0.5 0.5)
			(layers "F.Cu" "F.Mask" "F.Paste")
			(net 753 "Net-(U45C-CLKOUTB-)")
			(pinfunction "CLKOUTB-")
			(pintype "output")
			(solder_mask_margin 0.05)
			(teardrops
				(best_length_ratio 0.4)
				(max_length 1)
				(best_width_ratio 0.9)
				(max_width 2)
				(curved_edges yes)
				(filter_ratio 0.9)
				(enabled yes)
				(allow_two_segments yes)
				(prefer_zone_connections yes)
			)
		)
		(pad "A11" smd circle
			(at 4.5 -5.5 270)
			(size 0.5 0.5)
			(layers "F.Cu" "F.Mask" "F.Paste")
			(net 1 "GND")
			(pinfunction "GND")
			(pintype "power_in")
			(solder_mask_margin 0.05)
			(teardrops
				(best_length_ratio 0.4)
				(max_length 1)
				(best_width_ratio 0.9)
				(max_width 2)
				(curved_edges yes)
				(filter_ratio 0.9)
				(enabled yes)
				(allow_two_segments yes)
				(prefer_zone_connections yes)
			)
		)
		(pad "A12" smd circle
			(at 5.5 -5.5 270)
			(size 0.5 0.5)
			(layers "F.Cu" "F.Mask" "F.Paste")
			(net 122 "/2xSFP+/KR to SFI #2/KR_C.TX-")
			(pinfunction "HSRXA-")
			(pintype "input")
			(solder_mask_margin 0.05)
			(teardrops
				(best_length_ratio 0.4)
				(max_length 1)
				(best_width_ratio 0.9)
				(max_width 2)
				(curved_edges yes)
				(filter_ratio 0.9)
				(enabled yes)
				(allow_two_segments yes)
				(prefer_zone_connections yes)
			)
		)
		(pad "B1" smd circle
			(at -5.5 -4.5 270)
			(size 0.5 0.5)
			(layers "F.Cu" "F.Mask" "F.Paste")
			(net 837 "unconnected-(U45A-INA1--PadB1)")
			(pinfunction "INA1-")
			(pintype "input+no_connect")
			(solder_mask_margin 0.05)
			(teardrops
				(best_length_ratio 0.4)
				(max_length 1)
				(best_width_ratio 0.9)
				(max_width 2)
				(curved_edges yes)
				(filter_ratio 0.9)
				(enabled yes)
				(allow_two_segments yes)
				(prefer_zone_connections yes)
			)
		)
		(pad "B2" smd circle
			(at -4.5 -4.5 270)
			(size 0.5 0.5)
			(layers "F.Cu" "F.Mask" "F.Paste")
			(net 838 "unconnected-(U45A-INA2+-PadB2)")
			(pinfunction "INA2+")
			(pintype "input+no_connect")
			(solder_mask_margin 0.05)
			(teardrops
				(best_length_ratio 0.4)
				(max_length 1)
				(best_width_ratio 0.9)
				(max_width 2)
				(curved_edges yes)
				(filter_ratio 0.9)
				(enabled yes)
				(allow_two_segments yes)
				(prefer_zone_connections yes)
			)
		)
		(pad "B3" smd circle
			(at -3.5 -4.5 270)
			(size 0.5 0.5)
			(layers "F.Cu" "F.Mask" "F.Paste")
			(net 1 "GND")
			(pinfunction "GND")
			(pintype "passive")
			(solder_mask_margin 0.05)
			(teardrops
				(best_length_ratio 0.4)
				(max_length 1)
				(best_width_ratio 0.9)
				(max_width 2)
				(curved_edges yes)
				(filter_ratio 0.9)
				(enabled yes)
				(allow_two_segments yes)
				(prefer_zone_connections yes)
			)
		)
		(pad "B4" smd circle
			(at -2.5 -4.5 270)
			(size 0.5 0.5)
			(layers "F.Cu" "F.Mask" "F.Paste")
			(net 1 "GND")
			(pinfunction "GND")
			(pintype "passive")
			(solder_mask_margin 0.05)
			(teardrops
				(best_length_ratio 0.4)
				(max_length 1)
				(best_width_ratio 0.9)
				(max_width 2)
				(curved_edges yes)
				(filter_ratio 0.9)
				(enabled yes)
				(allow_two_segments yes)
				(prefer_zone_connections yes)
			)
		)
		(pad "B5" smd circle
			(at -1.5 -4.5 270)
			(size 0.5 0.5)
			(layers "F.Cu" "F.Mask" "F.Paste")
			(net 839 "unconnected-(U45A-OUTA1+-PadB5)")
			(pinfunction "OUTA1+")
			(pintype "output+no_connect")
			(solder_mask_margin 0.05)
			(teardrops
				(best_length_ratio 0.4)
				(max_length 1)
				(best_width_ratio 0.9)
				(max_width 2)
				(curved_edges yes)
				(filter_ratio 0.9)
				(enabled yes)
				(allow_two_segments yes)
				(prefer_zone_connections yes)
			)
		)
		(pad "B6" smd circle
			(at -0.5 -4.5 270)
			(size 0.5 0.5)
			(layers "F.Cu" "F.Mask" "F.Paste")
			(net 840 "unconnected-(U45A-OUTA1--PadB6)")
			(pinfunction "OUTA1-")
			(pintype "output+no_connect")
			(solder_mask_margin 0.05)
			(teardrops
				(best_length_ratio 0.4)
				(max_length 1)
				(best_width_ratio 0.9)
				(max_width 2)
				(curved_edges yes)
				(filter_ratio 0.9)
				(enabled yes)
				(allow_two_segments yes)
				(prefer_zone_connections yes)
			)
		)
		(pad "B7" smd circle
			(at 0.5 -4.5 270)
			(size 0.5 0.5)
			(layers "F.Cu" "F.Mask" "F.Paste")
			(net 1 "GND")
			(pinfunction "GND")
			(pintype "passive")
			(solder_mask_margin 0.05)
			(teardrops
				(best_length_ratio 0.4)
				(max_length 1)
				(best_width_ratio 0.9)
				(max_width 2)
				(curved_edges yes)
				(filter_ratio 0.9)
				(enabled yes)
				(allow_two_segments yes)
				(prefer_zone_connections yes)
			)
		)
		(pad "B8" smd circle
			(at 1.5 -4.5 270)
			(size 0.5 0.5)
			(layers "F.Cu" "F.Mask" "F.Paste")
			(net 744 "/2xSFP+/KR to SFI #2/TMS")
			(pinfunction "TMS")
			(pintype "input")
			(solder_mask_margin 0.05)
			(teardrops
				(best_length_ratio 0.4)
				(max_length 1)
				(best_width_ratio 0.9)
				(max_width 2)
				(curved_edges yes)
				(filter_ratio 0.9)
				(enabled yes)
				(allow_two_segments yes)
				(prefer_zone_connections yes)
			)
		)
		(pad "B9" smd circle
			(at 2.5 -4.5 270)
			(size 0.5 0.5)
			(layers "F.Cu" "F.Mask" "F.Paste")
			(net 673 "/2xSFP+/KR to SFI #2/PRBSEN")
			(pinfunction "PRBSEN")
			(pintype "input")
			(solder_mask_margin 0.05)
			(teardrops
				(best_length_ratio 0.4)
				(max_length 1)
				(best_width_ratio 0.9)
				(max_width 2)
				(curved_edges yes)
				(filter_ratio 0.9)
				(enabled yes)
				(allow_two_segments yes)
				(prefer_zone_connections yes)
			)
		)
		(pad "B10" smd circle
			(at 3.5 -4.5 270)
			(size 0.5 0.5)
			(layers "F.Cu" "F.Mask" "F.Paste")
			(net 755 "Net-(U45A-LS_OK_{IN_A})")
			(pinfunction "LS_OK_{IN_A}")
			(pintype "input")
			(solder_mask_margin 0.05)
			(teardrops
				(best_length_ratio 0.4)
				(max_length 1)
				(best_width_ratio 0.9)
				(max_width 2)
				(curved_edges yes)
				(filter_ratio 0.9)
				(enabled yes)
				(allow_two_segments yes)
				(prefer_zone_connections yes)
			)
		)
		(pad "B11" smd circle
			(at 4.5 -4.5 270)
			(size 0.5 0.5)
			(layers "F.Cu" "F.Mask" "F.Paste")
			(net 1 "GND")
			(pinfunction "GND")
			(pintype "passive")
			(solder_mask_margin 0.05)
			(teardrops
				(best_length_ratio 0.4)
				(max_length 1)
				(best_width_ratio 0.9)
				(max_width 2)
				(curved_edges yes)
				(filter_ratio 0.9)
				(enabled yes)
				(allow_two_segments yes)
				(prefer_zone_connections yes)
			)
		)
		(pad "B12" smd circle
			(at 5.5 -4.5 270)
			(size 0.5 0.5)
			(layers "F.Cu" "F.Mask" "F.Paste")
			(net 120 "/2xSFP+/KR to SFI #2/KR_C.TX+")
			(pinfunction "HSRXA+")
			(pintype "input")
			(solder_mask_margin 0.05)
			(teardrops
				(best_length_ratio 0.4)
				(max_length 1)
				(best_width_ratio 0.9)
				(max_width 2)
				(curved_edges yes)
				(filter_ratio 0.9)
				(enabled yes)
				(allow_two_segments yes)
				(prefer_zone_connections yes)
			)
		)
		(pad "C1" smd circle
			(at -5.5 -3.5 270)
			(size 0.5 0.5)
			(layers "F.Cu" "F.Mask" "F.Paste")
			(net 1 "GND")
			(pinfunction "GND")
			(pintype "passive")
			(solder_mask_margin 0.05)
			(teardrops
				(best_length_ratio 0.4)
				(max_length 1)
				(best_width_ratio 0.9)
				(max_width 2)
				(curved_edges yes)
				(filter_ratio 0.9)
				(enabled yes)
				(allow_two_segments yes)
				(prefer_zone_connections yes)
			)
		)
		(pad "C2" smd circle
			(at -4.5 -3.5 270)
			(size 0.5 0.5)
			(layers "F.Cu" "F.Mask" "F.Paste")
			(net 841 "unconnected-(U45A-INA2--PadC2)")
			(pinfunction "INA2-")
			(pintype "input+no_connect")
			(solder_mask_margin 0.05)
			(teardrops
				(best_length_ratio 0.4)
				(max_length 1)
				(best_width_ratio 0.9)
				(max_width 2)
				(curved_edges yes)
				(filter_ratio 0.9)
				(enabled yes)
				(allow_two_segments yes)
				(prefer_zone_connections yes)
			)
		)
		(pad "C3" smd circle
			(at -3.5 -3.5 270)
			(size 0.5 0.5)
			(layers "F.Cu" "F.Mask" "F.Paste")
			(net 78 "+1V8")
			(pinfunction "VDDRA_{LS/HS}")
			(pintype "power_in")
			(solder_mask_margin 0.05)
			(teardrops
				(best_length_ratio 0.4)
				(max_length 1)
				(best_width_ratio 0.9)
				(max_width 2)
				(curved_edges yes)
				(filter_ratio 0.9)
				(enabled yes)
				(allow_two_segments yes)
				(prefer_zone_connections yes)
			)
		)
		(pad "C4" smd circle
			(at -2.5 -3.5 270)
			(size 0.5 0.5)
			(layers "F.Cu" "F.Mask" "F.Paste")
			(net 842 "unconnected-(U45A-OUTA2+-PadC4)")
			(pinfunction "OUTA2+")
			(pintype "output+no_connect")
			(solder_mask_margin 0.05)
			(teardrops
				(best_length_ratio 0.4)
				(max_length 1)
				(best_width_ratio 0.9)
				(max_width 2)
				(curved_edges yes)
				(filter_ratio 0.9)
				(enabled yes)
				(allow_two_segments yes)
				(prefer_zone_connections yes)
			)
		)
		(pad "C5" smd circle
			(at -1.5 -3.5 270)
			(size 0.5 0.5)
			(layers "F.Cu" "F.Mask" "F.Paste")
			(net 843 "unconnected-(U45A-OUTA2--PadC5)")
			(pinfunction "OUTA2-")
			(pintype "output+no_connect")
			(solder_mask_margin 0.05)
			(teardrops
				(best_length_ratio 0.4)
				(max_length 1)
				(best_width_ratio 0.9)
				(max_width 2)
				(curved_edges yes)
				(filter_ratio 0.9)
				(enabled yes)
				(allow_two_segments yes)
				(prefer_zone_connections yes)
			)
		)
		(pad "C6" smd circle
			(at -0.5 -3.5 270)
			(size 0.5 0.5)
			(layers "F.Cu" "F.Mask" "F.Paste")
			(net 1 "GND")
			(pinfunction "GND")
			(pintype "passive")
			(solder_mask_margin 0.05)
			(teardrops
				(best_length_ratio 0.4)
				(max_length 1)
				(best_width_ratio 0.9)
				(max_width 2)
				(curved_edges yes)
				(filter_ratio 0.9)
				(enabled yes)
				(allow_two_segments yes)
				(prefer_zone_connections yes)
			)
		)
		(pad "C7" smd circle
			(at 0.5 -3.5 270)
			(size 0.5 0.5)
			(layers "F.Cu" "F.Mask" "F.Paste")
			(net 74 "+1V0")
			(pinfunction "VDDO0")
			(pintype "power_in")
			(solder_mask_margin 0.05)
			(teardrops
				(best_length_ratio 0.4)
				(max_length 1)
				(best_width_ratio 0.9)
				(max_width 2)
				(curved_edges yes)
				(filter_ratio 0.9)
				(enabled yes)
				(allow_two_segments yes)
				(prefer_zone_connections yes)
			)
		)
		(pad "C8" smd circle
			(at 1.5 -3.5 270)
			(size 0.5 0.5)
			(layers "F.Cu" "F.Mask" "F.Paste")
			(net 742 "/2xSFP+/KR to SFI #2/TDI")
			(pinfunction "TDI")
			(pintype "input")
			(solder_mask_margin 0.05)
			(teardrops
				(best_length_ratio 0.4)
				(max_length 1)
				(best_width_ratio 0.9)
				(max_width 2)
				(curved_edges yes)
				(filter_ratio 0.9)
				(enabled yes)
				(allow_two_segments yes)
				(prefer_zone_connections yes)
			)
		)
		(pad "C9" smd circle
			(at 2.5 -3.5 270)
			(size 0.5 0.5)
			(layers "F.Cu" "F.Mask" "F.Paste")
			(net 750 "Net-(U45C-CLKOUTA+)")
			(pinfunction "CLKOUTA+")
			(pintype "output")
			(solder_mask_margin 0.05)
			(teardrops
				(best_length_ratio 0.4)
				(max_length 1)
				(best_width_ratio 0.9)
				(max_width 2)
				(curved_edges yes)
				(filter_ratio 0.9)
				(enabled yes)
				(allow_two_segments yes)
				(prefer_zone_connections yes)
			)
		)
		(pad "C10" smd circle
			(at 3.5 -3.5 270)
			(size 0.5 0.5)
			(layers "F.Cu" "F.Mask" "F.Paste")
			(net 751 "Net-(U45C-CLKOUTA-)")
			(pinfunction "CLKOUTA-")
			(pintype "output")
			(solder_mask_margin 0.05)
			(teardrops
				(best_length_ratio 0.4)
				(max_length 1)
				(best_width_ratio 0.9)
				(max_width 2)
				(curved_edges yes)
				(filter_ratio 0.9)
				(enabled yes)
				(allow_two_segments yes)
				(prefer_zone_connections yes)
			)
		)
		(pad "C11" smd circle
			(at 4.5 -3.5 270)
			(size 0.5 0.5)
			(layers "F.Cu" "F.Mask" "F.Paste")
			(net 748 "Net-(U45C-AMUXA)")
			(pinfunction "AMUXA")
			(pintype "passive")
			(solder_mask_margin 0.05)
			(teardrops
				(best_length_ratio 0.4)
				(max_length 1)
				(best_width_ratio 0.9)
				(max_width 2)
				(curved_edges yes)
				(filter_ratio 0.9)
				(enabled yes)
				(allow_two_segments yes)
				(prefer_zone_connections yes)
			)
		)
		(pad "C12" smd circle
			(at 5.5 -3.5 270)
			(size 0.5 0.5)
			(layers "F.Cu" "F.Mask" "F.Paste")
			(net 1 "GND")
			(pinfunction "GND")
			(pintype "passive")
			(solder_mask_margin 0.05)
			(teardrops
				(best_length_ratio 0.4)
				(max_length 1)
				(best_width_ratio 0.9)
				(max_width 2)
				(curved_edges yes)
				(filter_ratio 0.9)
				(enabled yes)
				(allow_two_segments yes)
				(prefer_zone_connections yes)
			)
		)
		(pad "D1" smd circle
			(at -5.5 -2.5 270)
			(size 0.5 0.5)
			(layers "F.Cu" "F.Mask" "F.Paste")
			(net 844 "unconnected-(U45A-INA3+-PadD1)")
			(pinfunction "INA3+")
			(pintype "input+no_connect")
			(solder_mask_margin 0.05)
			(teardrops
				(best_length_ratio 0.4)
				(max_length 1)
				(best_width_ratio 0.9)
				(max_width 2)
				(curved_edges yes)
				(filter_ratio 0.9)
				(enabled yes)
				(allow_two_segments yes)
				(prefer_zone_connections yes)
			)
		)
		(pad "D2" smd circle
			(at -4.5 -2.5 270)
			(size 0.5 0.5)
			(layers "F.Cu" "F.Mask" "F.Paste")
			(net 74 "+1V0")
			(pinfunction "VDDA_{LS/HS}")
			(pintype "power_in")
			(solder_mask_margin 0.05)
			(teardrops
				(best_length_ratio 0.4)
				(max_length 1)
				(best_width_ratio 0.9)
				(max_width 2)
				(curved_edges yes)
				(filter_ratio 0.9)
				(enabled yes)
				(allow_two_segments yes)
				(prefer_zone_connections yes)
			)
		)
		(pad "D3" smd circle
			(at -3.5 -2.5 270)
			(size 0.5 0.5)
			(layers "F.Cu" "F.Mask" "F.Paste")
			(net 1 "GND")
			(pinfunction "GND")
			(pintype "passive")
			(solder_mask_margin 0.05)
			(teardrops
				(best_length_ratio 0.4)
				(max_length 1)
				(best_width_ratio 0.9)
				(max_width 2)
				(curved_edges yes)
				(filter_ratio 0.9)
				(enabled yes)
				(allow_two_segments yes)
				(prefer_zone_connections yes)
			)
		)
	)
)
